# Bryce Canyon_Rear_Drive_Plane_Board_Stackup.xlsx — Stack up_16317-1 (pcb-stackup)
|  |  |  |  |  |  | Version |  |  |  |  |  |  |  |  |  |  |  |  |  |  |  |  |  |  |  |
| Board Number: |  | 16317-1 |  |  |  | 02 |  |  |  |  |  |  |  |  |  |  |  |  |  |  |  |  |  |  |  |
| Project name: |  | Bryce Canyon |  |  |  |  |  |  |  |  |  |  |  |  |  |  |  |  |  |  |  |  |  |  |  |
| Model Name: |  | Rear Drive Plane Board |  |  |  |  |  |  |  |  |  |  |  |  |  |  |  |  |  |  |  |  |  |  |  |
| Layer Count: |  | 8 Layer |  |  |  |  |  |  |  |  |  |  |  |  |  |  |  |  |  |  |  |  |  |  |  |
| Date: |  | 2017-09-25 00:00:00 |  |  |  |  |  |  |  |  |  |  |  |  |  |  |  |  |  |  |  |  |  |  |  |
| Low Loss Material: |  | TU863+VLP (Tg : 180/Td : 375) |  |  |  |  |  |  | Single Ended Type(mil) |  |  |  |  | Differential Type(mil) |  |  |  |  |  |  |  |  |  |  |  |
| Gold Finger(Y/N): |  | N |  |  |  |  |  | Imp | 50 |  |  |  | Imp | 85 |  |  |  |  |  | 100 |  |  |  |  |  |
| Customer: |  | <name> |  |  |  |  |  | Variation | Inner/Outer+/-5ohm |  |  |  | Variation | Inner/Outer+/-10% |  |  |  |  |  | Inner/Outer+/-10% |  |  |  |  |  |
| EE engineer |  | <name> |  |  |  |  |  | Bus | MISC. |  |  |  | Bus | PCIe / Clock |  |  |  |  |  | SATA |  |  |  |  |  |
| SI Engineer |  | <name> |  |  |  |  |  |  |  |  |  |  |  |  |  |  |  |  |  |  |  |  |  |  |  |
|  |  |  |  |  |  |  |  | Type | SE |  |  |  | Type | DP |  |  |  |  |  | DP |  |  |  |  |  |
| Layer |  |  | Thickness |  | Glass/Copper Style | Er | Df(1G) | Layers | 1,3,6,8 |  |  |  | Layers | 1,3,6,8 |  |  |  |  |  | 1,3,6,8 |  |  |  |  |  |
|  |  | Cu oz | Wiwynn |  |  | Wiwynn |  |  | Wiwynn |  |  |  |  | Wiwynn |  |  |  |  |  | Wiwynn |  |  |  |  |  |
|  | Mask |  | 0.5 |  |  | 3.4 | 0.025 |  | Width | Imp | Width | Imp |  | Width | Space | Imp | Width | Space | Imp | Width | Space | Imp | Width | Space | Imp |
| Top | Signal | 0.5 oz+plating | 2.1 |  |  |  |  | S1 | 6.75(L2) | 50.17 |  |  | S1 | 6.5(L2) | 5 | 84.97 |  |  |  | 5(L2) | 6.5 | 99.87 |  |  |  |
|  | Prepreg |  | 4 |  |  | 3.9 | 0.006 |  |  |  |  |  |  |  |  |  |  |  |  |  |  |  |  |  |  |
| L2 | GND | 1 oz | 1.3 |  |  |  |  | P2 | reference layer |  |  |  | P2 | reference layer |  |  |  |  |  | reference layer |  |  |  |  |  |
|  | Core |  | 5 |  |  | 3.9 | 0.006 |  |  |  |  |  |  |  |  |  |  |  |  |  |  |  |  |  |  |
| L3 | Signal | 1 oz | 1.3 |  |  |  |  | S3 | 5.75(L2/L4) | 49.84 |  |  | S3 | 5.5(L2/L4) | 6 | 85.34 |  |  |  | 4.75(L2/L4) | 8.5 | 100.14 |  |  |  |
|  | Prepreg |  | 15 |  |  | 4.5 | 0.006 |  |  |  |  |  |  |  |  |  |  |  |  |  |  |  |  |  |  |
| L4 | POWER | 2 oz | 2.6 |  |  |  |  | P4 | reference layer |  |  |  | P4 | reference layer |  |  |  |  |  | reference layer |  |  |  |  |  |
|  | Core |  | 29.4 |  |  | 4.5 | 0.006 |  |  |  |  |  |  |  |  |  |  |  |  |  |  |  |  |  |  |
| L5 | POWER | 2 oz | 2.6 |  |  |  |  | P5 | reference layer |  |  |  | P5 | reference layer |  |  |  |  |  | reference layer |  |  |  |  |  |
|  | Prepreg |  | 15 |  |  | 4.5 | 0.006 |  |  |  |  |  |  |  |  |  |  |  |  |  |  |  |  |  |  |
| L6 | Signal | 1 oz | 1.3 | 0 | 0 |  |  | S6 | 5.75(L5/L7) | 49.84 |  |  | S6 | 5.5(L5/L7) | 6 | 85.34 |  |  |  | 4.75(L5/L7) | 8.5 | 100.14 |  |  |  |
|  | Core |  | 5 | 0 | 0 | 3.9 | 0.006 |  |  |  |  |  |  |  |  |  |  |  |  |  |  |  |  |  |  |
| L7 | GND | 1 oz | 1.3 | 0 | 0 |  |  | P7 | reference layer |  |  |  | P7 | reference layer |  |  |  |  |  | reference layer |  |  |  |  |  |
|  | Prepreg |  | 4 | 0 | 0 | 3.9 | 0.006 |  |  |  |  |  |  |  |  |  |  |  |  |  |  |  |  |  |  |
| Bottom | Signal | 0.5 oz+plating | 2.1 | 0 | 0 |  |  | S8 | 6.75(L7) | 50.17 |  |  | S8 | 6.5(L7) | 5 | 84.97 |  |  |  | 5(L7) | 6.5 | 99.87 |  |  |  |
|  | Mask |  | 0.5 | 0 |  | 3.4 | 0.025 |  |  |  |  |  |  |  |  |  |  |  |  |  |  |  |  |  |  |
| Thickness requirement: 2.36 ± 10% mm |  | mil | 93 |  |  |  |  |  |  |  |  |  |  |  |  |  |  |  |  |  |  |  |  |  |  |
|  |  | mm | 2.362204724409449 |  |  |  |  |  |  |  |  |  |  |  |  |  |  |  |  |  |  |  |  |  |  |
| Note: | 1. Unit is mil |  |  |  |  |  |  |  |  |  |  |  |  |  |  |  |  |  |  |  |  |  |  |  |  |
|  | 2. The total thickness includes trace and solder mask. |  |  |  |  |  |  |  |  |  |  |  |  |  |  |  |  |  |  |  |  |  |  |  |  |
|  | 3. Minimum hole copper thickness is 1.0 mil. |  |  |  |  |  |  |  |  |  |  |  |  |  |  |  |  |  |  |  |  |  |  |  |  |
|  | 4. Minimum surface copper thickness 1.5 mil. |  |  |  |  |  |  |  |  |  |  |  |  |  |  |  |  |  |  |  |  |  |  |  |  |
|  | 5. If there is no controlled impedance line described as the stackup in the gerber file, PCB supplier can ignore this kind of impedance control directly, but need to inform Wiwynn in engineering question(EQ). |  |  |  |  |  |  |  |  |  |  |  |  |  |  |  |  |  |  |  |  |  |  |  |  |
|  | 6. PCB test coupon requirement and PCB test note are described in the another sheets. |  |  |  |  |  |  |  |  |  |  |  |  |  |  |  |  |  |  |  |  |  |  |  |  |
|  | 7. If there is no "Delta-L" design in gerber file, PCB supplier should design 85 ohm "Delta-L" angle routing coupon and provide the measurement results in FAI report which meet the following criteria: |  |  |  |  |  |  |  |  |  |  |  |  |  |  |  |  |  |  |  |  |  |  |  |  |
|  | For low-loss material |  |  |  |  |  |  |  |  |  |  |  |  |  |  |  |  |  |  |  |  |  |  |  |  |
|  | (1)   0.55 dB/inch @ 4GHz; 1.05 dB/inch @ 8GHz for microstrip routing |  |  |  |  |  |  |  |  |  |  |  |  |  |  |  |  |  |  |  |  |  |  |  |  |
|  | (2)   0.48 dB/inch @ 4GHz; 0.9 dB/inch @ 8GHz for stripline routing |  |  |  |  |  |  |  |  |  |  |  |  |  |  |  |  |  |  |  |  |  |  |  |  |
